(kicad_pcb
	(version 20241229)
	(generator "pcbnew")
	(generator_version "9.0")
	(general
		(thickness 1.61)
		(legacy_teardrops no)
	)
	(paper "A3")
	(title_block
		(title "RDIMM DDR5 Tester")
		(date "2026-05-21")
		(rev "2.2.0")
		(company "Antmicro")
		(comment 9 "footprints 6-11 of 796")
	)
	(layers
		(0 "F.Cu" signal)
		(4 "In1.Cu" power)
		(6 "In2.Cu" mixed)
		(8 "In3.Cu" power)
		(10 "In4.Cu" mixed)
		(12 "In5.Cu" power)
		(14 "In6.Cu" mixed)
		(16 "In7.Cu" power)
		(18 "In8.Cu" power)
		(20 "In9.Cu" mixed)
		(22 "In10.Cu" power)
		(2 "B.Cu" signal)
		(9 "F.Adhes" user "F.Adhesive")
		(11 "B.Adhes" user "B.Adhesive")
		(13 "F.Paste" user)
		(15 "B.Paste" user)
		(5 "F.SilkS" user "F.Silkscreen")
		(7 "B.SilkS" user "B.Silkscreen")
		(1 "F.Mask" user)
		(3 "B.Mask" user)
		(17 "Dwgs.User" user "User.Drawings")
		(19 "Cmts.User" user "User.Comments")
		(21 "Eco1.User" user "User.Eco1")
		(23 "Eco2.User" user "User.Eco2")
		(25 "Edge.Cuts" user)
		(27 "Margin" user)
		(31 "F.CrtYd" user "F.Courtyard")
		(29 "B.CrtYd" user "B.Courtyard")
		(35 "F.Fab" user)
		(33 "B.Fab" user)
	)
	(footprint "antmicro-footprints:R_0402_1005Metric"
		(layer "F.Cu")
		(at 149.904499 159.709)
		(descr "Resistor SMD 0402")
		(tags "resistor SMD 0402")
		(property "Reference" "R54"
			(at -0.834499 -1.569 0)
			(layer "F.SilkS")
			(effects
				(font
					(size 0.7 0.7)
					(thickness 0.15)
				)
				(justify left bottom)
			)
		)
		(property "Value" "R_22R_0402"
			(at -1.011843 1.772047 0)
			(layer "F.Fab")
			(effects
				(font
					(size 0.7 0.7)
					(thickness 0.15)
				)
				(justify left bottom)
			)
		)
		(property "Datasheet" "https://www.bourns.com/docs/product-datasheets/cr.pdf"
			(at 0 0 0)
			(layer "F.Fab")
			(hide yes)
			(effects
				(font
					(size 1.27 1.27)
					(thickness 0.15)
				)
			)
		)
		(property "Manufacturer" "Bourns"
			(at 0 0 0)
			(unlocked yes)
			(layer "F.Fab")
			(hide yes)
			(effects
				(font
					(size 1 1)
					(thickness 0.15)
				)
			)
		)
		(property "MPN" "CR0402-FX-22R0GLF"
			(at 0 0 0)
			(unlocked yes)
			(layer "F.Fab")
			(hide yes)
			(effects
				(font
					(size 1 1)
					(thickness 0.15)
				)
			)
		)
		(property "Val" "22R"
			(at 0 0 0)
			(unlocked yes)
			(layer "F.Fab")
			(hide yes)
			(effects
				(font
					(size 1 1)
					(thickness 0.15)
				)
			)
		)
		(property "License" "Apache-2.0"
			(at 0 0 0)
			(unlocked yes)
			(layer "F.Fab")
			(hide yes)
			(effects
				(font
					(size 1 1)
					(thickness 0.15)
				)
			)
		)
		(property "Author" "Antmicro"
			(at 0 0 0)
			(unlocked yes)
			(layer "F.Fab")
			(hide yes)
			(effects
				(font
					(size 1 1)
					(thickness 0.15)
				)
			)
		)
		(property "Tolerance" "1%"
			(at 0 0 0)
			(unlocked yes)
			(layer "F.Fab")
			(hide yes)
			(effects
				(font
					(size 1 1)
					(thickness 0.15)
				)
			)
		)
		(sheetname "/Debug FTDI + VNA/")
		(sheetfile "debug-ftdi.kicad_sch")
		(attr smd)
		(fp_rect
			(start -0.925 -0.47)
			(end 0.925 0.47)
			(stroke
				(width 0.05)
				(type default)
			)
			(fill no)
			(layer "F.CrtYd")
		)
		(fp_rect
			(start -0.5 -0.25)
			(end 0.5 0.25)
			(stroke
				(width 0.15)
				(type solid)
			)
			(fill no)
			(layer "F.Fab")
		)
		(fp_text user "Author: Antmicro"
			(at -0.95 4.169 0)
			(layer "F.Fab")
			(effects
				(font
					(size 0.7 0.7)
					(thickness 0.15)
				)
				(justify left bottom)
			)
		)
		(fp_text user "License: Apache-2.0"
			(at -0.95 5.169 0)
			(layer "F.Fab")
			(effects
				(font
					(size 0.7 0.7)
					(thickness 0.15)
				)
				(justify left bottom)
			)
		)
		(fp_text user "${REFERENCE}"
			(at -0.95 3.168 0)
			(layer "F.Fab")
			(effects
				(font
					(size 0.7 0.7)
					(thickness 0.15)
				)
				(justify left bottom)
			)
		)
		(pad "1" smd roundrect
			(at -0.48 0)
			(size 0.59 0.64)
			(layers "F.Cu" "F.Mask" "F.Paste")
			(roundrect_rratio 0.25)
			(net 448 "Net-(U32-B1)")
			(pintype "passive")
		)
		(pad "2" smd roundrect
			(at 0.48 0)
			(size 0.59 0.64)
			(layers "F.Cu" "F.Mask" "F.Paste")
			(roundrect_rratio 0.25)
			(net 377 "/Debug FTDI + VNA/UART1.TX")
			(pintype "passive")
		)
	)
	(footprint "antmicro-footprints:R_0402_1005Metric"
		(layer "F.Cu")
		(at 149.904499 160.709)
		(descr "Resistor SMD 0402")
		(tags "resistor SMD 0402")
		(property "Reference" "R55"
			(at -0.834499 -1.569 0)
			(layer "F.SilkS")
			(effects
				(font
					(size 0.7 0.7)
					(thickness 0.15)
				)
				(justify left bottom)
			)
		)
		(property "Value" "R_22R_0402"
			(at -1.011843 1.772047 0)
			(layer "F.Fab")
			(effects
				(font
					(size 0.7 0.7)
					(thickness 0.15)
				)
				(justify left bottom)
			)
		)
		(property "Datasheet" "https://www.bourns.com/docs/product-datasheets/cr.pdf"
			(at 0 0 0)
			(layer "F.Fab")
			(hide yes)
			(effects
				(font
					(size 1.27 1.27)
					(thickness 0.15)
				)
			)
		)
		(property "Manufacturer" "Bourns"
			(at 0 0 0)
			(unlocked yes)
			(layer "F.Fab")
			(hide yes)
			(effects
				(font
					(size 1 1)
					(thickness 0.15)
				)
			)
		)
		(property "MPN" "CR0402-FX-22R0GLF"
			(at 0 0 0)
			(unlocked yes)
			(layer "F.Fab")
			(hide yes)
			(effects
				(font
					(size 1 1)
					(thickness 0.15)
				)
			)
		)
		(property "Val" "22R"
			(at 0 0 0)
			(unlocked yes)
			(layer "F.Fab")
			(hide yes)
			(effects
				(font
					(size 1 1)
					(thickness 0.15)
				)
			)
		)
		(property "License" "Apache-2.0"
			(at 0 0 0)
			(unlocked yes)
			(layer "F.Fab")
			(hide yes)
			(effects
				(font
					(size 1 1)
					(thickness 0.15)
				)
			)
		)
		(property "Author" "Antmicro"
			(at 0 0 0)
			(unlocked yes)
			(layer "F.Fab")
			(hide yes)
			(effects
				(font
					(size 1 1)
					(thickness 0.15)
				)
			)
		)
		(property "Tolerance" "1%"
			(at 0 0 0)
			(unlocked yes)
			(layer "F.Fab")
			(hide yes)
			(effects
				(font
					(size 1 1)
					(thickness 0.15)
				)
			)
		)
		(sheetname "/Debug FTDI + VNA/")
		(sheetfile "debug-ftdi.kicad_sch")
		(attr smd)
		(fp_rect
			(start -0.925 -0.47)
			(end 0.925 0.47)
			(stroke
				(width 0.05)
				(type default)
			)
			(fill no)
			(layer "F.CrtYd")
		)
		(fp_rect
			(start -0.5 -0.25)
			(end 0.5 0.25)
			(stroke
				(width 0.15)
				(type solid)
			)
			(fill no)
			(layer "F.Fab")
		)
		(fp_text user "${REFERENCE}"
			(at -0.95 3.168 0)
			(layer "F.Fab")
			(effects
				(font
					(size 0.7 0.7)
					(thickness 0.15)
				)
				(justify left bottom)
			)
		)
		(fp_text user "License: Apache-2.0"
			(at -0.95 5.169 0)
			(layer "F.Fab")
			(effects
				(font
					(size 0.7 0.7)
					(thickness 0.15)
				)
				(justify left bottom)
			)
		)
		(fp_text user "Author: Antmicro"
			(at -0.95 4.169 0)
			(layer "F.Fab")
			(effects
				(font
					(size 0.7 0.7)
					(thickness 0.15)
				)
				(justify left bottom)
			)
		)
		(pad "1" smd roundrect
			(at -0.48 0)
			(size 0.59 0.64)
			(layers "F.Cu" "F.Mask" "F.Paste")
			(roundrect_rratio 0.25)
			(net 449 "Net-(U32-B2)")
			(pintype "passive")
		)
		(pad "2" smd roundrect
			(at 0.48 0)
			(size 0.59 0.64)
			(layers "F.Cu" "F.Mask" "F.Paste")
			(roundrect_rratio 0.25)
			(net 378 "/Debug FTDI + VNA/UART1.RX")
			(pintype "passive")
		)
	)
	(footprint "antmicro-footprints:R_0402_1005Metric"
		(layer "F.Cu")
		(at 137.624499 173.049 -90)
		(descr "Resistor SMD 0402")
		(tags "resistor SMD 0402")
		(property "Reference" "R48"
			(at 1.127672 -0.427658 90)
			(layer "F.SilkS")
			(effects
				(font
					(size 0.7 0.7)
					(thickness 0.15)
				)
				(justify right bottom)
			)
		)
		(property "Value" "R_22R_0402"
			(at -1.011843 1.772047 90)
			(layer "F.Fab")
			(effects
				(font
					(size 0.7 0.7)
					(thickness 0.15)
				)
				(justify right bottom)
			)
		)
		(property "Datasheet" "https://www.bourns.com/docs/product-datasheets/cr.pdf"
			(at 0 0 270)
			(layer "F.Fab")
			(hide yes)
			(effects
				(font
					(size 1.27 1.27)
					(thickness 0.15)
				)
			)
		)
		(property "Manufacturer" "Bourns"
			(at 0 0 270)
			(unlocked yes)
			(layer "F.Fab")
			(hide yes)
			(effects
				(font
					(size 1 1)
					(thickness 0.15)
				)
			)
		)
		(property "MPN" "CR0402-FX-22R0GLF"
			(at 0 0 270)
			(unlocked yes)
			(layer "F.Fab")
			(hide yes)
			(effects
				(font
					(size 1 1)
					(thickness 0.15)
				)
			)
		)
		(property "Val" "22R"
			(at 0 0 270)
			(unlocked yes)
			(layer "F.Fab")
			(hide yes)
			(effects
				(font
					(size 1 1)
					(thickness 0.15)
				)
			)
		)
		(property "License" "Apache-2.0"
			(at 0 0 270)
			(unlocked yes)
			(layer "F.Fab")
			(hide yes)
			(effects
				(font
					(size 1 1)
					(thickness 0.15)
				)
			)
		)
		(property "Author" "Antmicro"
			(at 0 0 270)
			(unlocked yes)
			(layer "F.Fab")
			(hide yes)
			(effects
				(font
					(size 1 1)
					(thickness 0.15)
				)
			)
		)
		(property "Tolerance" "1%"
			(at 0 0 270)
			(unlocked yes)
			(layer "F.Fab")
			(hide yes)
			(effects
				(font
					(size 1 1)
					(thickness 0.15)
				)
			)
		)
		(sheetname "/Debug FTDI + VNA/")
		(sheetfile "debug-ftdi.kicad_sch")
		(attr smd)
		(fp_rect
			(start -0.925 -0.47)
			(end 0.925 0.47)
			(stroke
				(width 0.05)
				(type default)
			)
			(fill no)
			(layer "F.CrtYd")
		)
		(fp_rect
			(start -0.5 -0.25)
			(end 0.5 0.25)
			(stroke
				(width 0.15)
				(type solid)
			)
			(fill no)
			(layer "F.Fab")
		)
		(fp_text user "Author: Antmicro"
			(at -0.95 4.169 270)
			(layer "F.Fab")
			(effects
				(font
					(size 0.7 0.7)
					(thickness 0.15)
				)
				(justify left bottom)
			)
		)
		(fp_text user "License: Apache-2.0"
			(at -0.95 5.169 270)
			(layer "F.Fab")
			(effects
				(font
					(size 0.7 0.7)
					(thickness 0.15)
				)
				(justify left bottom)
			)
		)
		(fp_text user "${REFERENCE}"
			(at -0.95 3.168 270)
			(layer "F.Fab")
			(effects
				(font
					(size 0.7 0.7)
					(thickness 0.15)
				)
				(justify left bottom)
			)
		)
		(pad "1" smd roundrect
			(at -0.48 0 270)
			(size 0.59 0.64)
			(layers "F.Cu" "F.Mask" "F.Paste")
			(roundrect_rratio 0.25)
			(net 298 "Net-(U7-B2Y)")
			(pintype "passive")
		)
		(pad "2" smd roundrect
			(at 0.48 0 270)
			(size 0.59 0.64)
			(layers "F.Cu" "F.Mask" "F.Paste")
			(roundrect_rratio 0.25)
			(net 239 "/Debug FTDI + VNA/JTAG.TCK")
			(pintype "passive")
		)
	)
	(footprint "antmicro-footprints:R_0402_1005Metric"
		(layer "F.Cu")
		(at 135.424499 173.049 -90)
		(descr "Resistor SMD 0402")
		(tags "resistor SMD 0402")
		(property "Reference" "R50"
			(at 1.127672 -0.427658 90)
			(layer "F.SilkS")
			(effects
				(font
					(size 0.7 0.7)
					(thickness 0.15)
				)
				(justify right bottom)
			)
		)
		(property "Value" "R_22R_0402"
			(at -1.011843 1.772047 90)
			(layer "F.Fab")
			(effects
				(font
					(size 0.7 0.7)
					(thickness 0.15)
				)
				(justify right bottom)
			)
		)
		(property "Datasheet" "https://www.bourns.com/docs/product-datasheets/cr.pdf"
			(at 0 0 270)
			(layer "F.Fab")
			(hide yes)
			(effects
				(font
					(size 1.27 1.27)
					(thickness 0.15)
				)
			)
		)
		(property "Manufacturer" "Bourns"
			(at 0 0 270)
			(unlocked yes)
			(layer "F.Fab")
			(hide yes)
			(effects
				(font
					(size 1 1)
					(thickness 0.15)
				)
			)
		)
		(property "MPN" "CR0402-FX-22R0GLF"
			(at 0 0 270)
			(unlocked yes)
			(layer "F.Fab")
			(hide yes)
			(effects
				(font
					(size 1 1)
					(thickness 0.15)
				)
			)
		)
		(property "Val" "22R"
			(at 0 0 270)
			(unlocked yes)
			(layer "F.Fab")
			(hide yes)
			(effects
				(font
					(size 1 1)
					(thickness 0.15)
				)
			)
		)
		(property "License" "Apache-2.0"
			(at 0 0 270)
			(unlocked yes)
			(layer "F.Fab")
			(hide yes)
			(effects
				(font
					(size 1 1)
					(thickness 0.15)
				)
			)
		)
		(property "Author" "Antmicro"
			(at 0 0 270)
			(unlocked yes)
			(layer "F.Fab")
			(hide yes)
			(effects
				(font
					(size 1 1)
					(thickness 0.15)
				)
			)
		)
		(property "Tolerance" "1%"
			(at 0 0 270)
			(unlocked yes)
			(layer "F.Fab")
			(hide yes)
			(effects
				(font
					(size 1 1)
					(thickness 0.15)
				)
			)
		)
		(sheetname "/Debug FTDI + VNA/")
		(sheetfile "debug-ftdi.kicad_sch")
		(attr smd)
		(fp_rect
			(start -0.925 -0.47)
			(end 0.925 0.47)
			(stroke
				(width 0.05)
				(type default)
			)
			(fill no)
			(layer "F.CrtYd")
		)
		(fp_rect
			(start -0.5 -0.25)
			(end 0.5 0.25)
			(stroke
				(width 0.15)
				(type solid)
			)
			(fill no)
			(layer "F.Fab")
		)
		(fp_text user "Author: Antmicro"
			(at -0.95 4.169 270)
			(layer "F.Fab")
			(effects
				(font
					(size 0.7 0.7)
					(thickness 0.15)
				)
				(justify left bottom)
			)
		)
		(fp_text user "License: Apache-2.0"
			(at -0.95 5.169 270)
			(layer "F.Fab")
			(effects
				(font
					(size 0.7 0.7)
					(thickness 0.15)
				)
				(justify left bottom)
			)
		)
		(fp_text user "${REFERENCE}"
			(at -0.95 3.168 270)
			(layer "F.Fab")
			(effects
				(font
					(size 0.7 0.7)
					(thickness 0.15)
				)
				(justify left bottom)
			)
		)
		(pad "1" smd roundrect
			(at -0.48 0 270)
			(size 0.59 0.64)
			(layers "F.Cu" "F.Mask" "F.Paste")
			(roundrect_rratio 0.25)
			(net 300 "Net-(U7-B4)")
			(pintype "passive")
		)
		(pad "2" smd roundrect
			(at 0.48 0 270)
			(size 0.59 0.64)
			(layers "F.Cu" "F.Mask" "F.Paste")
			(roundrect_rratio 0.25)
			(net 242 "/Debug FTDI + VNA/JTAG.TDO")
			(pintype "passive")
		)
	)
	(footprint "antmicro-footprints:R_0402_1005Metric"
		(layer "F.Cu")
		(at 136.547342 173.047328 -90)
		(descr "Resistor SMD 0402")
		(tags "resistor SMD 0402")
		(property "Reference" "R49"
			(at 1.127672 -0.427658 90)
			(layer "F.SilkS")
			(effects
				(font
					(size 0.7 0.7)
					(thickness 0.15)
				)
				(justify right bottom)
			)
		)
		(property "Value" "R_22R_0402"
			(at -1.011843 1.772047 90)
			(layer "F.Fab")
			(effects
				(font
					(size 0.7 0.7)
					(thickness 0.15)
				)
				(justify right bottom)
			)
		)
		(property "Datasheet" "https://www.bourns.com/docs/product-datasheets/cr.pdf"
			(at 0 0 270)
			(layer "F.Fab")
			(hide yes)
			(effects
				(font
					(size 1.27 1.27)
					(thickness 0.15)
				)
			)
		)
		(property "Manufacturer" "Bourns"
			(at 0 0 270)
			(unlocked yes)
			(layer "F.Fab")
			(hide yes)
			(effects
				(font
					(size 1 1)
					(thickness 0.15)
				)
			)
		)
		(property "MPN" "CR0402-FX-22R0GLF"
			(at 0 0 270)
			(unlocked yes)
			(layer "F.Fab")
			(hide yes)
			(effects
				(font
					(size 1 1)
					(thickness 0.15)
				)
			)
		)
		(property "Val" "22R"
			(at 0 0 270)
			(unlocked yes)
			(layer "F.Fab")
			(hide yes)
			(effects
				(font
					(size 1 1)
					(thickness 0.15)
				)
			)
		)
		(property "License" "Apache-2.0"
			(at 0 0 270)
			(unlocked yes)
			(layer "F.Fab")
			(hide yes)
			(effects
				(font
					(size 1 1)
					(thickness 0.15)
				)
			)
		)
		(property "Author" "Antmicro"
			(at 0 0 270)
			(unlocked yes)
			(layer "F.Fab")
			(hide yes)
			(effects
				(font
					(size 1 1)
					(thickness 0.15)
				)
			)
		)
		(property "Tolerance" "1%"
			(at 0 0 270)
			(unlocked yes)
			(layer "F.Fab")
			(hide yes)
			(effects
				(font
					(size 1 1)
					(thickness 0.15)
				)
			)
		)
		(sheetname "/Debug FTDI + VNA/")
		(sheetfile "debug-ftdi.kicad_sch")
		(attr smd)
		(fp_rect
			(start -0.925 -0.47)
			(end 0.925 0.47)
			(stroke
				(width 0.05)
				(type default)
			)
			(fill no)
			(layer "F.CrtYd")
		)
		(fp_rect
			(start -0.5 -0.25)
			(end 0.5 0.25)
			(stroke
				(width 0.15)
				(type solid)
			)
			(fill no)
			(layer "F.Fab")
		)
		(fp_text user "License: Apache-2.0"
			(at -0.95 5.169 270)
			(layer "F.Fab")
			(effects
				(font
					(size 0.7 0.7)
					(thickness 0.15)
				)
				(justify left bottom)
			)
		)
		(fp_text user "Author: Antmicro"
			(at -0.95 4.169 270)
			(layer "F.Fab")
			(effects
				(font
					(size 0.7 0.7)
					(thickness 0.15)
				)
				(justify left bottom)
			)
		)
		(fp_text user "${REFERENCE}"
			(at -0.95 3.168 270)
			(layer "F.Fab")
			(effects
				(font
					(size 0.7 0.7)
					(thickness 0.15)
				)
				(justify left bottom)
			)
		)
		(pad "1" smd roundrect
			(at -0.48 0 270)
			(size 0.59 0.64)
			(layers "F.Cu" "F.Mask" "F.Paste")
			(roundrect_rratio 0.25)
			(net 299 "Net-(U7-B3Y)")
			(pintype "passive")
		)
		(pad "2" smd roundrect
			(at 0.48 0 270)
			(size 0.59 0.64)
			(layers "F.Cu" "F.Mask" "F.Paste")
			(roundrect_rratio 0.25)
			(net 244 "/Debug FTDI + VNA/JTAG.TDI")
			(pintype "passive")
		)
	)
	(footprint "antmicro-footprints:R_0402_1005Metric"
		(layer "F.Cu")
		(at 138.724499 173.049 -90)
		(descr "Resistor SMD 0402")
		(tags "resistor SMD 0402")
		(property "Reference" "R47"
			(at 1.127672 -0.427658 90)
			(layer "F.SilkS")
			(effects
				(font
					(size 0.7 0.7)
					(thickness 0.15)
				)
				(justify right bottom)
			)
		)
		(property "Value" "R_22R_0402"
			(at -1.011843 1.772047 90)
			(layer "F.Fab")
			(effects
				(font
					(size 0.7 0.7)
					(thickness 0.15)
				)
				(justify right bottom)
			)
		)
		(property "Datasheet" "https://www.bourns.com/docs/product-datasheets/cr.pdf"
			(at 0 0 270)
			(layer "F.Fab")
			(hide yes)
			(effects
				(font
					(size 1.27 1.27)
					(thickness 0.15)
				)
			)
		)
		(property "Manufacturer" "Bourns"
			(at 0 0 270)
			(unlocked yes)
			(layer "F.Fab")
			(hide yes)
			(effects
				(font
					(size 1 1)
					(thickness 0.15)
				)
			)
		)
		(property "MPN" "CR0402-FX-22R0GLF"
			(at 0 0 270)
			(unlocked yes)
			(layer "F.Fab")
			(hide yes)
			(effects
				(font
					(size 1 1)
					(thickness 0.15)
				)
			)
		)
		(property "Val" "22R"
			(at 0 0 270)
			(unlocked yes)
			(layer "F.Fab")
			(hide yes)
			(effects
				(font
					(size 1 1)
					(thickness 0.15)
				)
			)
		)
		(property "License" "Apache-2.0"
			(at 0 0 270)
			(unlocked yes)
			(layer "F.Fab")
			(hide yes)
			(effects
				(font
					(size 1 1)
					(thickness 0.15)
				)
			)
		)
		(property "Author" "Antmicro"
			(at 0 0 270)
			(unlocked yes)
			(layer "F.Fab")
			(hide yes)
			(effects
				(font
					(size 1 1)
					(thickness 0.15)
				)
			)
		)
		(property "Tolerance" "1%"
			(at 0 0 270)
			(unlocked yes)
			(layer "F.Fab")
			(hide yes)
			(effects
				(font
					(size 1 1)
					(thickness 0.15)
				)
			)
		)
		(sheetname "/Debug FTDI + VNA/")
		(sheetfile "debug-ftdi.kicad_sch")
		(attr smd)
		(fp_rect
			(start -0.925 -0.47)
			(end 0.925 0.47)
			(stroke
				(width 0.05)
				(type default)
			)
			(fill no)
			(layer "F.CrtYd")
		)
		(fp_rect
			(start -0.5 -0.25)
			(end 0.5 0.25)
			(stroke
				(width 0.15)
				(type solid)
			)
			(fill no)
			(layer "F.Fab")
		)
		(fp_text user "License: Apache-2.0"
			(at -0.95 5.169 270)
			(layer "F.Fab")
			(effects
				(font
					(size 0.7 0.7)
					(thickness 0.15)
				)
				(justify left bottom)
			)
		)
		(fp_text user "${REFERENCE}"
			(at -0.95 3.168 270)
			(layer "F.Fab")
			(effects
				(font
					(size 0.7 0.7)
					(thickness 0.15)
				)
				(justify left bottom)
			)
		)
		(fp_text user "Author: Antmicro"
			(at -0.95 4.169 270)
			(layer "F.Fab")
			(effects
				(font
					(size 0.7 0.7)
					(thickness 0.15)
				)
				(justify left bottom)
			)
		)
		(pad "1" smd roundrect
			(at -0.48 0 270)
			(size 0.59 0.64)
			(layers "F.Cu" "F.Mask" "F.Paste")
			(roundrect_rratio 0.25)
			(net 296 "Net-(U7-B1Y)")
			(pintype "passive")
		)
		(pad "2" smd roundrect
			(at 0.48 0 270)
			(size 0.59 0.64)
			(layers "F.Cu" "F.Mask" "F.Paste")
			(roundrect_rratio 0.25)
			(net 238 "/Debug FTDI + VNA/JTAG.TMS")
			(pintype "passive")
		)
	)
)
